FILE_TYPE = CONNECTIVITY;
{Allegro Design Entry HDL 16.6-p007 (v16-6-112F) 10/10/2012}
"PAGE_NUMBER" = 52;
0"NC";
1"M_E_DQS_DP<17:0>";
2"M_E_DQS_DN<17:0>";
3"M_E_DQ<63:0>";
4"M_E_ECC<7:0>";
5"M_E_ODT<3:0>";
6"M_E_CS_N<7:0>";
7"M_E_CKE<3:0>";
8"M_E_CLK_DP<3:0>";
9"M_E_CLK_DN<3:0>";
10"M_E_BA<1:0>";
11"M_E_BG<1:0>";
12"M_E_MA<17:0>";
13"GND\g";
14"GND\g";
15"GND\g";
16"P12V_NVDIMM_DEF\g";
17"GND\g";
18"PVPP_DEF\g";
19"PVDDQ_DEF\g";
20"PVTT_DEF\g";
21"PVPP_DEF\g";
22"M_E_MA<1>";
23"M_E_VREF";
24"M_E_DQ<63>";
25"M_E_DQ<60>";
26"M_E_DQ<58>";
27"M_E_DQ<57>";
28"M_E_MA<10>";
29"M_E_DQ<12>";
30"M_E_DQ<50>";
31"M_E_DQ<33>";
32"M_E_DQ<54>";
33"M_E_DQ<5>";
34"M_E_DQ<8>";
35"M_E_DQ<9>";
36"M_E_DQ<10>";
37"M_E_DQ<11>";
38"M_E_DQS_DP<2>";
39"M_E_DQS_DN<3>";
40"M_E_DQS_DN<17>";
41"M_E_DQS_DP<17>";
42"M_E_DQS_DP<16>";
43"M_E_DQS_DN<16>";
44"M_E_DQS_DN<15>";
45"M_E_DQS_DN<14>";
46"M_E_DQS_DN<13>";
47"M_E_DQS_DN<12>";
48"M_E_DQS_DN<11>";
49"M_E_DQS_DP<15>";
50"M_E_DQS_DP<14>";
51"M_E_DQS_DP<13>";
52"M_E_DQS_DP<12>";
53"M_E_DQS_DP<11>";
54"M_E_DQS_DN<9>";
55"M_E_DQS_DN<8>";
56"M_E_DQS_DN<7>";
57"M_E_DQS_DN<6>";
58"M_E_DQS_DN<10>";
59"M_E_DQS_DP<9>";
60"M_E_DQS_DP<8>";
61"M_E_DQS_DP<10>";
62"M_E_DQS_DP<7>";
63"M_E_DQS_DP<6>";
64"M_E_DQS_DN<5>";
65"M_E_DQS_DN<4>";
66"M_E_DQS_DN<2>";
67"M_E_DQS_DN<1>";
68"M_E_DQS_DP<5>";
69"M_E_DQS_DP<4>";
70"M_E_DQS_DP<3>";
71"M_E_DQS_DP<0>";
72"M_E_DQ<61>";
73"M_E_DQ<62>";
74"M_E_DQ<55>";
75"M_E_DQ<56>";
76"M_E_DQ<59>";
77"M_E_MA<16>";
78"M_E_MA<15>";
79"M_E_MA<14>";
80"M_E_MA<11>";
81"M_E_MA<9>";
82"M_E_MA<17>";
83"M_E_MA<13>";
84"M_E_MA<12>";
85"M_E_DQ<51>";
86"M_E_DQ<52>";
87"M_E_DQ<53>";
88"M_E_DQ<47>";
89"M_E_DQ<48>";
90"M_E_DQ<49>";
91"M_E_DQ<45>";
92"M_E_DQ<46>";
93"M_E_DQ<40>";
94"M_E_DQ<41>";
95"M_E_DQ<42>";
96"M_E_DQ<43>";
97"M_E_DQ<44>";
98"M_E_DQ<38>";
99"M_E_DQ<36>";
100"M_E_DQ<35>";
101"M_E_DQ<37>";
102"M_E_DQ<39>";
103"M_E_DQ<30>";
104"M_E_DQ<31>";
105"M_E_DQ<32>";
106"M_E_DQ<34>";
107"M_E_DQ<26>";
108"M_E_DQ<27>";
109"M_E_DQ<25>";
110"M_E_DQ<28>";
111"M_E_DQ<29>";
112"M_E_DQ<20>";
113"M_E_DQ<21>";
114"M_E_DQ<22>";
115"M_E_DQ<23>";
116"M_E_DQ<24>";
117"M_E_DQ<17>";
118"M_E_DQ<15>";
119"M_E_DQ<14>";
120"M_E_DQ<16>";
121"M_E_DQ<18>";
122"M_E_DQ<19>";
123"M_E_MA<2>";
124"M_E_MA<8>";
125"M_E_MA<7>";
126"M_E_MA<6>";
127"M_E_MA<5>";
128"M_E_MA<4>";
129"M_E_MA<3>";
130"M_E_MA<0>";
131"M_E_BA<0>";
132"M_E_BG<1>";
133"M_E_BG<0>";
134"M_E_BA<1>";
135"M_E_CLK_DN<2>";
136"M_E_CLK_DN<3>";
137"M_E_CLK_DP<3>";
138"M_E_CLK_DP<2>";
139"M_E_C<2>";
140"M_E_CS_N<4>";
141"M_E_CKE<2>";
142"M_E_ODT<3>";
143"M_E_CKE<3>";
144"M_E_CS_N<5>";
145"M_E_CS_N<6>";
146"M_E_CS_N<7>";
147"M_E_ODT<2>";
148"M_E_ECC<7>";
149"M_E_ECC<0>";
150"M_E_ECC<1>";
151"M_E_ECC<2>";
152"M_E_ECC<3>";
153"M_E_ECC<4>";
154"M_E_ECC<5>";
155"M_E_ECC<6>";
156"M_E_PAR";
157"FM_DIMM_EVENT_COD_N";
158"M_DEF_RST_N";
159"M_E_DQ<13>";
160"M_E_DQ<4>";
161"M_E_DQ<6>";
162"M_E_DQ<7>";
163"M_E_DQ<3>";
164"M_E_DQ<2>";
165"M_E_DQ<0>";
166"M_E_DQ<1>";
167"SMB_DDR_DEF_VPP_SCL";
168"SMB_DDR_DEF_VPP_SDA";
169"FM_ADR_COMPLETE_DEF_N";
170"M_E_ACT_N";
171"M_E_ALERT_N";
172"TP_CH_E_DIMM_E1_RFU_1";
173"TP_CH_E_DIMM_E1_RFU_0";
174"TP_CH_E_DIMM_E1_RFU_2";
175"M_E_DQS_DN<0>";
176"M_E_DQS_DP<1>";
%"GND"
"1","(-3575,1500)","2","mstr_symbols","I1";
;
VOLTAGE"0"
CDS_LIB"mstr_symbols"
SIZE"1B"
BODY_TYPE"PLUMBING"
HDL_POWER"GND";
"A\NAC"13;
%"SCONN288_H44441003"
"2","(1625,3900)","0","mstr_sconn","I100";
;
CDS_SEC"2"
LOCATION"J6L2"
PART_NUMBER"H44441-003"
MATERIAL"SCONN"
BOM_SS"NOPOP"
PACK_TYPE"PIP"
BOM_COST"MEM"
CDS_LIB"mstr_sconn"
SEC_TYPE"PIP"
SEC"2"
CDS_LOCATION"J6L2"
ROOM"DDR4_CH_E";
"DQS0N"
$PN"152"175;
"DQS0P"
$PN"153"71;
"DQS10N"
$PN"19"58;
"DQS10P"
$PN"18"61;
"DQS11N"
$PN"30"48;
"DQS11P"
$PN"29"53;
"DQS12N"
$PN"41"47;
"DQS12P"
$PN"40"52;
"DQS13N"
$PN"100"46;
"DQS13P"
$PN"99"51;
"DQS14N"
$PN"111"45;
"DQS14P"
$PN"110"50;
"DQS15N"
$PN"122"44;
"DQS15P"
$PN"121"49;
"DQS16N"
$PN"133"43;
"DQS16P"
$PN"132"42;
"DQS17N"
$PN"52"40;
"DQS17P"
$PN"51"41;
"DQS1N"
$PN"163"67;
"DQS1P"
$PN"164"176;
"DQS2N"
$PN"174"66;
"DQS2P"
$PN"175"38;
"DQS3N"
$PN"185"39;
"DQS3P"
$PN"186"70;
"DQS4N"
$PN"244"65;
"DQS4P"
$PN"245"69;
"DQS5N"
$PN"255"64;
"DQS5P"
$PN"256"68;
"DQS6N"
$PN"266"57;
"DQS6P"
$PN"267"63;
"DQS7N"
$PN"277"56;
"DQS7P"
$PN"278"62;
"DQS8N"
$PN"196"55;
"DQS8P"
$PN"197"60;
"DQS9N"
$PN"8"54;
"DQS9P"
$PN"7"59;
%"TAP"
"6","(-1475,3750)","0","mstr_standard","I102";
;
CDS_LIB"mstr_standard"
BODY_TYPE"PLUMBING"
HDL_TAP"TRUE";
"B \NAC \NWC"12;
"S \NAC"
BN"2"123;
%"TAP"
"6","(-1475,3700)","0","mstr_standard","I103";
;
CDS_LIB"mstr_standard"
BODY_TYPE"PLUMBING"
HDL_TAP"TRUE";
"B \NAC \NWC"12;
"S \NAC"
BN"1"22;
%"TAP"
"6","(-1475,3800)","0","mstr_standard","I104";
;
CDS_LIB"mstr_standard"
BODY_TYPE"PLUMBING"
HDL_TAP"TRUE";
"B \NAC \NWC"12;
"S \NAC"
BN"3"129;
%"TAP"
"6","(-1475,3900)","0","mstr_standard","I105";
;
CDS_LIB"mstr_standard"
BODY_TYPE"PLUMBING"
HDL_TAP"TRUE";
"B \NAC \NWC"12;
"S \NAC"
BN"5"127;
%"TAP"
"6","(-1475,3850)","0","mstr_standard","I106";
;
CDS_LIB"mstr_standard"
BODY_TYPE"PLUMBING"
HDL_TAP"TRUE";
"B \NAC \NWC"12;
"S \NAC"
BN"4"128;
%"TAP"
"6","(-1475,3950)","0","mstr_standard","I107";
;
CDS_LIB"mstr_standard"
BODY_TYPE"PLUMBING"
HDL_TAP"TRUE";
"B \NAC \NWC"12;
"S \NAC"
BN"6"126;
%"TAP"
"6","(-1475,4050)","0","mstr_standard","I108";
;
CDS_LIB"mstr_standard"
BODY_TYPE"PLUMBING"
HDL_TAP"TRUE";
"B \NAC \NWC"12;
"S \NAC"
BN"8"124;
%"TAP"
"6","(-1475,4000)","0","mstr_standard","I109";
;
CDS_LIB"mstr_standard"
BODY_TYPE"PLUMBING"
HDL_TAP"TRUE";
"B \NAC \NWC"12;
"S \NAC"
BN"7"125;
%"TAP"
"6","(-1475,4150)","0","mstr_standard","I110";
;
CDS_LIB"mstr_standard"
BODY_TYPE"PLUMBING"
HDL_TAP"TRUE";
"B \NAC \NWC"12;
"S \NAC"
BN"10"28;
%"TAP"
"6","(-1475,4100)","0","mstr_standard","I111";
;
CDS_LIB"mstr_standard"
BODY_TYPE"PLUMBING"
HDL_TAP"TRUE";
"B \NAC \NWC"12;
"S \NAC"
BN"9"81;
%"TAP"
"6","(-1475,4200)","0","mstr_standard","I112";
;
CDS_LIB"mstr_standard"
BODY_TYPE"PLUMBING"
HDL_TAP"TRUE";
"B \NAC \NWC"12;
"S \NAC"
BN"11"80;
%"TAP"
"6","(-1475,4300)","0","mstr_standard","I113";
;
CDS_LIB"mstr_standard"
BODY_TYPE"PLUMBING"
HDL_TAP"TRUE";
"B \NAC \NWC"12;
"S \NAC"
BN"13"83;
%"TAP"
"6","(-1475,4250)","0","mstr_standard","I114";
;
CDS_LIB"mstr_standard"
BODY_TYPE"PLUMBING"
HDL_TAP"TRUE";
"B \NAC \NWC"12;
"S \NAC"
BN"12"84;
%"TAP"
"6","(-1475,4400)","0","mstr_standard","I115";
;
CDS_LIB"mstr_standard"
BODY_TYPE"PLUMBING"
HDL_TAP"TRUE";
"B \NAC \NWC"12;
"S \NAC"
BN"15"78;
%"TAP"
"6","(-1475,4350)","0","mstr_standard","I116";
;
CDS_LIB"mstr_standard"
BODY_TYPE"PLUMBING"
HDL_TAP"TRUE";
"B \NAC \NWC"12;
"S \NAC"
BN"14"79;
%"TAP"
"6","(-1475,4450)","0","mstr_standard","I117";
;
CDS_LIB"mstr_standard"
BODY_TYPE"PLUMBING"
HDL_TAP"TRUE";
"B \NAC \NWC"12;
"S \NAC"
BN"16"77;
%"TAP"
"6","(-1475,4500)","0","mstr_standard","I118";
;
CDS_LIB"mstr_standard"
BODY_TYPE"PLUMBING"
HDL_TAP"TRUE";
"B \NAC \NWC"12;
"S \NAC"
BN"17"82;
%"TAP"
"6","(25,3800)","2","mstr_standard","I119";
;
CDS_LIB"mstr_standard"
BODY_TYPE"PLUMBING"
HDL_TAP"TRUE";
"B \NAC \NWC"3;
"S \NAC"
BN"49"90;
%"SCONN288_H44441003"
"1","(-725,2850)","0","mstr_sconn","I12";
;
CDS_SEC"1"
LOCATION"J6L2"
MATERIAL"SCONN"
PART_NUMBER"H44441-003"
BOM_SS"NOPOP"
PACK_TYPE"PIP"
BOM_COST"MEM"
CDS_LIB"mstr_sconn"
SEC_TYPE"PIP"
SEC"1"
CDS_LOCATION"J6L2"
ROOM"DDR4_CH_E";
"DQ<63>"
$PN"280"24;
"BA<1>"
$PN"224"134;
"CK1N"
$PN"219"136;
"CK0P"
$PN"74"138;
"S3_N_C<1>"
$PN"237"146;
"S2_N_C<0>"
$PN"93"145;
"S1_N"
$PN"89"144;
"DQ<29>"
$PN"181"111;
"DQ<28>"
$PN"36"110;
"C<2>"
$PN"235"139;
"A0"
$PN"79"130;
"A1"
$PN"72"22;
"A12"
$PN"65"84;
"A13"
$PN"232"83;
"A17"
$PN"234"82;
"A3"
$PN"71"129;
"A4"
$PN"214"128;
"A5"
$PN"213"127;
"A6"
$PN"69"126;
"A7"
$PN"211"125;
"A8"
$PN"68"124;
"A9"
$PN"66"81;
"CB<6>"
$PN"54"155;
"CB<5>"
$PN"192"154;
"CB<4>"
$PN"47"153;
"CB<3>"
$PN"201"152;
"CB<2>"
$PN"56"151;
"CB<1>"
$PN"194"150;
"CB<0>"
$PN"49"149;
"CK0N"
$PN"75"135;
"CKE<1>"
$PN"203"143;
"DQ<62>"
$PN"135"73;
"DQ<61>"
$PN"273"72;
"DQ<60>"
$PN"128"25;
"DQ<59>"
$PN"282"76;
"DQ<56>"
$PN"130"75;
"DQ<55>"
$PN"269"74;
"DQ<46>"
$PN"113"92;
"DQ<45>"
$PN"251"91;
"DQ<44>"
$PN"106"97;
"DQ<43>"
$PN"260"96;
"DQ<42>"
$PN"115"95;
"DQ<41>"
$PN"253"94;
"DQ<40>"
$PN"108"93;
"DQ<39>"
$PN"247"102;
"DQ<37>"
$PN"240"101;
"DQ<34>"
$PN"104"106;
"DQ<33>"
$PN"242"31;
"DQ<32>"
$PN"97"105;
"DQ<31>"
$PN"188"104;
"DQ<30>"
$PN"43"103;
"DQ<25>"
$PN"183"109;
"DQ<24>"
$PN"38"116;
"DQ<23>"
$PN"177"115;
"DQ<22>"
$PN"32"114;
"DQ<21>"
$PN"170"113;
"DQ<20>"
$PN"25"112;
"DQ<19>"
$PN"179"122;
"DQ<18>"
$PN"34"121;
"DQ<16>"
$PN"27"120;
"DQ<14>"
$PN"21"119;
"DQ<13>"
$PN"159"159;
"DQ<12>"
$PN"14"29;
"DQ<11>"
$PN"168"37;
"DQ<10>"
$PN"23"36;
"DQ<9>"
$PN"161"35;
"DQ<8>"
$PN"16"34;
"DQ<7>"
$PN"155"162;
"DQ<6>"
$PN"10"161;
"EVENT_N"
$PN"78"157;
"PAR"
$PN"222"156;
"RESET_N"
$PN"58"158;
"RFU<2>"
$PN"144"174;
"SCL"
$PN"141"167;
"SDA"
$PN"285"168;
"VREFCA"
$PN"146"23;
"CK1P"
$PN"218"137;
"BG<0>"
$PN"63"133;
"BG<1>"
$PN"207"132;
"BA<0>"
$PN"81"131;
"SA<0>"
$PN"139"18;
"VDDSPD"
$PN"284"18;
"SA<2>"
$PN"238"13;
"SA<1>"
$PN"140"18;
"DQ<1>"
$PN"150"166;
"DQ<0>"
$PN"5"165;
"ACT_N"
$PN"62"170;
"ALERT_N"
$PN"208"171;
"A2"
$PN"216"123;
"DQ<35>"
$PN"249"100;
"DQ<36>"
$PN"95"99;
"DQ<38>"
$PN"102"98;
"A10"
$PN"225"28;
"A11"
$PN"210"80;
"A14_WE_N"
$PN"228"79;
"A15_CAS_N"
$PN"86"78;
"A16_RAS_N"
$PN"82"77;
"CB<7>"
$PN"199"148;
"ODT<0>"
$PN"87"147;
"ODT<1>"
$PN"91"142;
"CKE<0>"
$PN"60"141;
"S0_N"
$PN"84"140;
"DQ<27>"
$PN"190"108;
"DQ<26>"
$PN"45"107;
"DQ<15>"
$PN"166"118;
"DQ<17>"
$PN"172"117;
"RFU<0>"
$PN"205"173;
"RFU<1>"
$PN"227"172;
"SAVE_N_NC"
$PN"230"169;
"DQ<57>"
$PN"275"27;
"DQ<58>"
$PN"137"26;
"DQ<54>"
$PN"124"32;
"DQ<53>"
$PN"262"87;
"DQ<52>"
$PN"117"86;
"DQ<51>"
$PN"271"85;
"DQ<50>"
$PN"126"30;
"DQ<49>"
$PN"264"90;
"DQ<48>"
$PN"119"89;
"DQ<47>"
$PN"258"88;
"DQ<2>"
$PN"12"164;
"DQ<3>"
$PN"157"163;
"DQ<4>"
$PN"3"160;
"DQ<5>"
$PN"148"33;
%"TAP"
"6","(25,3700)","2","mstr_standard","I120";
;
CDS_LIB"mstr_standard"
BODY_TYPE"PLUMBING"
HDL_TAP"TRUE";
"B \NAC \NWC"3;
"S \NAC"
BN"47"88;
%"TAP"
"6","(25,3750)","2","mstr_standard","I121";
;
CDS_LIB"mstr_standard"
BODY_TYPE"PLUMBING"
HDL_TAP"TRUE";
"B \NAC \NWC"3;
"S \NAC"
BN"48"89;
%"TAP"
"6","(25,3950)","2","mstr_standard","I122";
;
CDS_LIB"mstr_standard"
BODY_TYPE"PLUMBING"
HDL_TAP"TRUE";
"B \NAC \NWC"3;
"S \NAC"
BN"52"86;
%"TAP"
"6","(25,3900)","2","mstr_standard","I123";
;
CDS_LIB"mstr_standard"
BODY_TYPE"PLUMBING"
HDL_TAP"TRUE";
"B \NAC \NWC"3;
"S \NAC"
BN"51"85;
%"TAP"
"6","(25,3850)","2","mstr_standard","I124";
;
CDS_LIB"mstr_standard"
BODY_TYPE"PLUMBING"
HDL_TAP"TRUE";
"B \NAC \NWC"3;
"S \NAC"
BN"50"30;
%"TAP"
"6","(25,4000)","2","mstr_standard","I125";
;
CDS_LIB"mstr_standard"
BODY_TYPE"PLUMBING"
HDL_TAP"TRUE";
"B \NAC \NWC"3;
"S \NAC"
BN"53"87;
%"TAP"
"6","(25,4050)","2","mstr_standard","I126";
;
CDS_LIB"mstr_standard"
BODY_TYPE"PLUMBING"
HDL_TAP"TRUE";
"B \NAC \NWC"3;
"S \NAC"
BN"54"32;
%"TAP"
"6","(25,4200)","2","mstr_standard","I127";
;
CDS_LIB"mstr_standard"
BODY_TYPE"PLUMBING"
HDL_TAP"TRUE";
"B \NAC \NWC"3;
"S \NAC"
BN"57"27;
%"TAP"
"6","(25,4150)","2","mstr_standard","I128";
;
CDS_LIB"mstr_standard"
BODY_TYPE"PLUMBING"
HDL_TAP"TRUE";
"B \NAC \NWC"3;
"S \NAC"
BN"56"75;
%"TAP"
"6","(25,4100)","2","mstr_standard","I129";
;
CDS_LIB"mstr_standard"
BODY_TYPE"PLUMBING"
HDL_TAP"TRUE";
"B \NAC \NWC"3;
"S \NAC"
BN"55"74;
%"TAP"
"6","(25,4300)","2","mstr_standard","I130";
;
CDS_LIB"mstr_standard"
BODY_TYPE"PLUMBING"
HDL_TAP"TRUE";
"B \NAC \NWC"3;
"S \NAC"
BN"59"76;
%"TAP"
"6","(25,4250)","2","mstr_standard","I131";
;
CDS_LIB"mstr_standard"
BODY_TYPE"PLUMBING"
HDL_TAP"TRUE";
"B \NAC \NWC"3;
"S \NAC"
BN"58"26;
%"TAP"
"6","(25,4450)","2","mstr_standard","I132";
;
CDS_LIB"mstr_standard"
BODY_TYPE"PLUMBING"
HDL_TAP"TRUE";
"B \NAC \NWC"3;
"S \NAC"
BN"62"73;
%"TAP"
"6","(25,4350)","2","mstr_standard","I133";
;
CDS_LIB"mstr_standard"
BODY_TYPE"PLUMBING"
HDL_TAP"TRUE";
"B \NAC \NWC"3;
"S \NAC"
BN"60"25;
%"TAP"
"6","(25,4400)","2","mstr_standard","I134";
;
CDS_LIB"mstr_standard"
BODY_TYPE"PLUMBING"
HDL_TAP"TRUE";
"B \NAC \NWC"3;
"S \NAC"
BN"61"72;
%"TAP"
"6","(25,4500)","2","mstr_standard","I135";
;
CDS_LIB"mstr_standard"
BODY_TYPE"PLUMBING"
HDL_TAP"TRUE";
"B \NAC \NWC"3;
"S \NAC"
BN"63"24;
%"GND"
"1","(2725,800)","2","mstr_symbols","I137";
;
VOLTAGE"0"
CDS_LIB"mstr_symbols"
SIZE"1B"
BODY_TYPE"PLUMBING"
HDL_POWER"GND";
"A\NAC"14;
%"SCONN288_H44441003"
"3","(3425,2100)","0","mstr_sconn","I138";
;
CDS_SEC"3"
LOCATION"J6L2"
PART_NUMBER"H44441-003"
MATERIAL"SCONN"
BOM_SS"NOPOP"
PACK_TYPE"PIP"
BOM_COST"MEM"
CDS_LIB"mstr_sconn"
SEC_TYPE"PIP"
SEC"3"
CDS_LOCATION"J6L2"
ROOM"DDR4_CH_E";
"VSS<46>"
$PN"147"15;
"VSS<45>"
$PN"149"15;
"VSS<87>"
$PN"15"14;
"VSS<86>"
$PN"17"14;
"VSS<85>"
$PN"20"14;
"VSS<84>"
$PN"22"14;
"VSS<83>"
$PN"24"14;
"VSS<82>"
$PN"26"14;
"VSS<81>"
$PN"28"14;
"VSS<80>"
$PN"31"14;
"VSS<79>"
$PN"33"14;
"VSS<78>"
$PN"35"14;
"VSS<77>"
$PN"37"14;
"VSS<76>"
$PN"39"14;
"VSS<75>"
$PN"42"14;
"VSS<74>"
$PN"44"14;
"VSS<73>"
$PN"46"14;
"VSS<72>"
$PN"48"14;
"VSS<71>"
$PN"50"14;
"VSS<70>"
$PN"53"14;
"VSS<69>"
$PN"55"14;
"VSS<68>"
$PN"57"14;
"VSS<67>"
$PN"94"14;
"VSS<66>"
$PN"96"14;
"VSS<65>"
$PN"98"14;
"VSS<64>"
$PN"101"14;
"VSS<63>"
$PN"103"14;
"VSS<62>"
$PN"105"14;
"VSS<61>"
$PN"107"14;
"VSS<60>"
$PN"109"14;
"VSS<59>"
$PN"112"14;
"VSS<58>"
$PN"114"14;
"VSS<57>"
$PN"116"14;
"VSS<56>"
$PN"118"14;
"VSS<55>"
$PN"120"14;
"VSS<54>"
$PN"123"14;
"VSS<53>"
$PN"125"14;
"VSS<52>"
$PN"127"14;
"VSS<51>"
$PN"129"14;
"VSS<50>"
$PN"131"14;
"VSS<49>"
$PN"134"14;
"VSS<48>"
$PN"136"14;
"VSS<47>"
$PN"138"14;
"VSS<44>"
$PN"151"15;
"VSS<43>"
$PN"154"15;
"VSS<42>"
$PN"156"15;
"VSS<41>"
$PN"158"15;
"VSS<40>"
$PN"160"15;
"VSS<39>"
$PN"162"15;
"VSS<38>"
$PN"165"15;
"VSS<37>"
$PN"167"15;
"VSS<36>"
$PN"169"15;
"VSS<35>"
$PN"171"15;
"VSS<34>"
$PN"173"15;
"VSS<33>"
$PN"176"15;
"VSS<32>"
$PN"178"15;
"VSS<31>"
$PN"180"15;
"VSS<30>"
$PN"182"15;
"VSS<29>"
$PN"184"15;
"VSS<28>"
$PN"187"15;
"VSS<27>"
$PN"189"15;
"VSS<26>"
$PN"191"15;
"VSS<25>"
$PN"193"15;
"VSS<24>"
$PN"195"15;
"VSS<23>"
$PN"198"15;
"VSS<22>"
$PN"200"15;
"VSS<21>"
$PN"202"15;
"VSS<20>"
$PN"239"15;
"VSS<19>"
$PN"241"15;
"VSS<18>"
$PN"243"15;
"VSS<17>"
$PN"246"15;
"VSS<16>"
$PN"248"15;
"VSS<15>"
$PN"250"15;
"VSS<14>"
$PN"252"15;
"VSS<13>"
$PN"254"15;
"VSS<12>"
$PN"257"15;
"VSS<11>"
$PN"259"15;
"VSS<10>"
$PN"261"15;
"VSS<9>"
$PN"263"15;
"VSS<8>"
$PN"265"15;
"VSS<7>"
$PN"268"15;
"VSS<6>"
$PN"270"15;
"VSS<5>"
$PN"272"15;
"VSS<4>"
$PN"274"15;
"VSS<3>"
$PN"276"15;
"VSS<2>"
$PN"279"15;
"VSS<1>"
$PN"281"15;
"VSS<0>"
$PN"283"15;
"VSS<88>"
$PN"13"14;
"VSS<89>"
$PN"11"14;
"VSS<90>"
$PN"9"14;
"VSS<91>"
$PN"6"14;
"VSS<92>"
$PN"4"14;
"VSS<93>"
$PN"2"14;
%"TAP"
"6","(2325,3050)","2","mstr_standard","I142";
;
CDS_LIB"mstr_standard"
BODY_TYPE"PLUMBING"
HDL_TAP"TRUE";
"B \NAC \NWC"1;
"S \NAC"
BN"0"71;
%"TAP"
"6","(2325,3150)","2","mstr_standard","I143";
;
CDS_LIB"mstr_standard"
BODY_TYPE"PLUMBING"
HDL_TAP"TRUE";
"B \NAC \NWC"1;
"S \NAC"
BN"1"176;
%"TAP"
"6","(2525,3000)","2","mstr_standard","I144";
;
CDS_LIB"mstr_standard"
BODY_TYPE"PLUMBING"
HDL_TAP"TRUE";
"B \NAC \NWC"2;
"S \NAC"
BN"0"175;
%"TAP"
"6","(2525,3100)","2","mstr_standard","I145";
;
CDS_LIB"mstr_standard"
BODY_TYPE"PLUMBING"
HDL_TAP"TRUE";
"B \NAC \NWC"2;
"S \NAC"
BN"1"67;
%"TAP"
"6","(2325,3250)","2","mstr_standard","I146";
;
CDS_LIB"mstr_standard"
BODY_TYPE"PLUMBING"
HDL_TAP"TRUE";
"B \NAC \NWC"1;
"S \NAC"
BN"2"38;
%"TAP"
"6","(2325,3350)","2","mstr_standard","I147";
;
CDS_LIB"mstr_standard"
BODY_TYPE"PLUMBING"
HDL_TAP"TRUE";
"B \NAC \NWC"1;
"S \NAC"
BN"3"70;
%"TAP"
"6","(2325,3450)","2","mstr_standard","I148";
;
CDS_LIB"mstr_standard"
BODY_TYPE"PLUMBING"
HDL_TAP"TRUE";
"B \NAC \NWC"1;
"S \NAC"
BN"4"69;
%"TAP"
"6","(2325,3550)","2","mstr_standard","I149";
;
CDS_LIB"mstr_standard"
BODY_TYPE"PLUMBING"
HDL_TAP"TRUE";
"B \NAC \NWC"1;
"S \NAC"
BN"5"68;
%"TAP"
"6","(2325,3650)","2","mstr_standard","I150";
;
CDS_LIB"mstr_standard"
BODY_TYPE"PLUMBING"
HDL_TAP"TRUE";
"B \NAC \NWC"1;
"S \NAC"
BN"6"63;
%"TAP"
"6","(2525,3400)","2","mstr_standard","I151";
;
CDS_LIB"mstr_standard"
BODY_TYPE"PLUMBING"
HDL_TAP"TRUE";
"B \NAC \NWC"2;
"S \NAC"
BN"4"65;
%"TAP"
"6","(2525,3200)","2","mstr_standard","I152";
;
CDS_LIB"mstr_standard"
BODY_TYPE"PLUMBING"
HDL_TAP"TRUE";
"B \NAC \NWC"2;
"S \NAC"
BN"2"66;
%"TAP"
"6","(2525,3300)","2","mstr_standard","I153";
;
CDS_LIB"mstr_standard"
BODY_TYPE"PLUMBING"
HDL_TAP"TRUE";
"B \NAC \NWC"2;
"S \NAC"
BN"3"39;
%"TAP"
"6","(2525,3600)","2","mstr_standard","I154";
;
CDS_LIB"mstr_standard"
BODY_TYPE"PLUMBING"
HDL_TAP"TRUE";
"B \NAC \NWC"2;
"S \NAC"
BN"6"57;
%"TAP"
"6","(2525,3500)","2","mstr_standard","I155";
;
CDS_LIB"mstr_standard"
BODY_TYPE"PLUMBING"
HDL_TAP"TRUE";
"B \NAC \NWC"2;
"S \NAC"
BN"5"64;
%"GND"
"1","(4125,800)","2","mstr_symbols","I156";
;
VOLTAGE"0"
CDS_LIB"mstr_symbols"
SIZE"1B"
BODY_TYPE"PLUMBING"
HDL_POWER"GND";
"A\NAC"15;
%"TAP"
"6","(2325,3750)","2","mstr_standard","I157";
;
CDS_LIB"mstr_standard"
BODY_TYPE"PLUMBING"
HDL_TAP"TRUE";
"B \NAC \NWC"1;
"S \NAC"
BN"7"62;
%"TAP"
"6","(2325,3950)","2","mstr_standard","I158";
;
CDS_LIB"mstr_standard"
BODY_TYPE"PLUMBING"
HDL_TAP"TRUE";
"B \NAC \NWC"1;
"S \NAC"
BN"9"59;
%"TAP"
"6","(2325,3850)","2","mstr_standard","I159";
;
CDS_LIB"mstr_standard"
BODY_TYPE"PLUMBING"
HDL_TAP"TRUE";
"B \NAC \NWC"1;
"S \NAC"
BN"8"60;
%"TAP"
"6","(2325,4050)","2","mstr_standard","I160";
;
CDS_LIB"mstr_standard"
BODY_TYPE"PLUMBING"
HDL_TAP"TRUE";
"B \NAC \NWC"1;
"S \NAC"
BN"10"61;
%"TAP"
"6","(2325,4150)","2","mstr_standard","I161";
;
CDS_LIB"mstr_standard"
BODY_TYPE"PLUMBING"
HDL_TAP"TRUE";
"B \NAC \NWC"1;
"S \NAC"
BN"11"53;
%"TAP"
"6","(2525,3900)","2","mstr_standard","I162";
;
CDS_LIB"mstr_standard"
BODY_TYPE"PLUMBING"
HDL_TAP"TRUE";
"B \NAC \NWC"2;
"S \NAC"
BN"9"54;
%"TAP"
"6","(2525,3700)","2","mstr_standard","I163";
;
CDS_LIB"mstr_standard"
BODY_TYPE"PLUMBING"
HDL_TAP"TRUE";
"B \NAC \NWC"2;
"S \NAC"
BN"7"56;
%"TAP"
"6","(2525,3800)","2","mstr_standard","I164";
;
CDS_LIB"mstr_standard"
BODY_TYPE"PLUMBING"
HDL_TAP"TRUE";
"B \NAC \NWC"2;
"S \NAC"
BN"8"55;
%"TAP"
"6","(2525,4100)","2","mstr_standard","I165";
;
CDS_LIB"mstr_standard"
BODY_TYPE"PLUMBING"
HDL_TAP"TRUE";
"B \NAC \NWC"2;
"S \NAC"
BN"11"48;
%"TAP"
"6","(2525,4000)","2","mstr_standard","I166";
;
CDS_LIB"mstr_standard"
BODY_TYPE"PLUMBING"
HDL_TAP"TRUE";
"B \NAC \NWC"2;
"S \NAC"
BN"10"58;
%"TAP"
"6","(2525,4200)","2","mstr_standard","I167";
;
CDS_LIB"mstr_standard"
BODY_TYPE"PLUMBING"
HDL_TAP"TRUE";
"B \NAC \NWC"2;
"S \NAC"
BN"12"47;
%"TAP"
"6","(2325,4250)","2","mstr_standard","I168";
;
CDS_LIB"mstr_standard"
BODY_TYPE"PLUMBING"
HDL_TAP"TRUE";
"B \NAC \NWC"1;
"S \NAC"
BN"12"52;
%"TAP"
"6","(2325,4450)","2","mstr_standard","I169";
;
CDS_LIB"mstr_standard"
BODY_TYPE"PLUMBING"
HDL_TAP"TRUE";
"B \NAC \NWC"1;
"S \NAC"
BN"14"50;
%"TAP"
"6","(2325,4350)","2","mstr_standard","I170";
;
CDS_LIB"mstr_standard"
BODY_TYPE"PLUMBING"
HDL_TAP"TRUE";
"B \NAC \NWC"1;
"S \NAC"
BN"13"51;
%"TAP"
"6","(2325,4550)","2","mstr_standard","I171";
;
CDS_LIB"mstr_standard"
BODY_TYPE"PLUMBING"
HDL_TAP"TRUE";
"B \NAC \NWC"1;
"S \NAC"
BN"15"49;
%"TAP"
"6","(2325,4650)","2","mstr_standard","I172";
;
CDS_LIB"mstr_standard"
BODY_TYPE"PLUMBING"
HDL_TAP"TRUE";
"B \NAC \NWC"1;
"S \NAC"
BN"16"42;
%"TAP"
"6","(2525,4400)","2","mstr_standard","I173";
;
CDS_LIB"mstr_standard"
BODY_TYPE"PLUMBING"
HDL_TAP"TRUE";
"B \NAC \NWC"2;
"S \NAC"
BN"14"45;
%"TAP"
"6","(2525,4300)","2","mstr_standard","I174";
;
CDS_LIB"mstr_standard"
BODY_TYPE"PLUMBING"
HDL_TAP"TRUE";
"B \NAC \NWC"2;
"S \NAC"
BN"13"46;
%"TAP"
"6","(2525,4700)","2","mstr_standard","I175";
;
CDS_LIB"mstr_standard"
BODY_TYPE"PLUMBING"
HDL_TAP"TRUE";
"B \NAC \NWC"2;
"S \NAC"
BN"17"40;
%"TAP"
"6","(2525,4600)","2","mstr_standard","I176";
;
CDS_LIB"mstr_standard"
BODY_TYPE"PLUMBING"
HDL_TAP"TRUE";
"B \NAC \NWC"2;
"S \NAC"
BN"16"43;
%"TAP"
"6","(2525,4500)","2","mstr_standard","I177";
;
CDS_LIB"mstr_standard"
BODY_TYPE"PLUMBING"
HDL_TAP"TRUE";
"B \NAC \NWC"2;
"S \NAC"
BN"15"44;
%"TAP"
"6","(2325,4750)","2","mstr_standard","I178";
;
CDS_LIB"mstr_standard"
BODY_TYPE"PLUMBING"
HDL_TAP"TRUE";
"B \NAC \NWC"1;
"S \NAC"
BN"17"41;
%"P12V_NVDIMM_DEF"
"1","(2175,2725)","0","mstr_symbols","I181";
;
VOLTAGE"12.0"
CDS_LIB"mstr_symbols"
BODY_TYPE"PLUMBING"
HDL_POWER"P12V_NVDIMM_DEF";
"G\NAC"16;
%"TAP"
"6","(-1475,2100)","0","mstr_standard","I19";
;
CDS_LIB"mstr_standard"
BODY_TYPE"PLUMBING"
HDL_TAP"TRUE";
"B \NAC \NWC"4;
"S \NAC"
BN"0"149;
%"GND"
"1","(-3025,900)","2","mstr_symbols","I2";
;
VOLTAGE"0"
SIZE"1B"
CDS_LIB"mstr_symbols"
BODY_TYPE"PLUMBING"
HDL_POWER"GND";
"A\NAC"17;
%"TAP"
"6","(-1475,2150)","0","mstr_standard","I20";
;
CDS_LIB"mstr_standard"
BODY_TYPE"PLUMBING"
HDL_TAP"TRUE";
"B \NAC \NWC"4;
"S \NAC"
BN"1"150;
%"TAP"
"6","(-1475,2250)","0","mstr_standard","I21";
;
CDS_LIB"mstr_standard"
BODY_TYPE"PLUMBING"
HDL_TAP"TRUE";
"B \NAC \NWC"4;
"S \NAC"
BN"3"152;
%"TAP"
"6","(-1475,2200)","0","mstr_standard","I22";
;
CDS_LIB"mstr_standard"
BODY_TYPE"PLUMBING"
HDL_TAP"TRUE";
"B \NAC \NWC"4;
"S \NAC"
BN"2"151;
%"TAP"
"6","(-1475,2350)","0","mstr_standard","I23";
;
CDS_LIB"mstr_standard"
BODY_TYPE"PLUMBING"
HDL_TAP"TRUE";
"B \NAC \NWC"4;
"S \NAC"
BN"5"154;
%"TAP"
"6","(-1475,2300)","0","mstr_standard","I24";
;
CDS_LIB"mstr_standard"
BODY_TYPE"PLUMBING"
HDL_TAP"TRUE";
"B \NAC \NWC"4;
"S \NAC"
BN"4"153;
%"TAP"
"6","(-1475,2400)","0","mstr_standard","I25";
;
CDS_LIB"mstr_standard"
BODY_TYPE"PLUMBING"
HDL_TAP"TRUE";
"B \NAC \NWC"4;
"S \NAC"
BN"6"155;
%"TAP"
"6","(-1475,2450)","0","mstr_standard","I26";
;
CDS_LIB"mstr_standard"
BODY_TYPE"PLUMBING"
HDL_TAP"TRUE";
"B \NAC \NWC"4;
"S \NAC"
BN"7"148;
%"TAP"
"6","(-1475,2600)","0","mstr_standard","I27";
;
CDS_LIB"mstr_standard"
BODY_TYPE"PLUMBING"
HDL_TAP"TRUE";
"B \NAC \NWC"5;
"S \NAC"
BN"3"142;
%"TAP"
"6","(-1475,2550)","0","mstr_standard","I28";
;
CDS_LIB"mstr_standard"
BODY_TYPE"PLUMBING"
HDL_TAP"TRUE";
"B \NAC \NWC"5;
"S \NAC"
BN"2"147;
%"CAP_A"
"1","(-3025,1150)","2","dev_discrete","I3";
;
CDS_SEC"1"
LOCATION"C4A18"
PART_NUMBER"A36096-045"
TOLERANCE"10%"
MATERIAL"X7R"
VALUE"0.01UF"
VOLTAGE"25V"
PACK_TYPE"0402V"
CDS_LOCATION"C4A18"
BOM_COST"MEM"
CDS_LIB"dev_discrete"
ROOM"DDR4_CH_E"
SEC"1"
SEC_TYPE"0402V";
"B"
$PN"2"17;
"A"
$PN"1"23;
%"TAP"
"6","(-2025,3150)","0","mstr_standard","I32";
;
CDS_LIB"mstr_standard"
BODY_TYPE"PLUMBING"
HDL_TAP"TRUE";
"B \NAC \NWC"9;
"S \NAC"
BN"2"135;
%"TAP"
"6","(-2025,3250)","0","mstr_standard","I35";
;
CDS_LIB"mstr_standard"
BODY_TYPE"PLUMBING"
HDL_TAP"TRUE";
"B \NAC \NWC"9;
"S \NAC"
BN"3"136;
%"TAP"
"6","(-1525,2750)","0","mstr_standard","I36";
;
CDS_LIB"mstr_standard"
BODY_TYPE"PLUMBING"
HDL_TAP"TRUE";
"B \NAC \NWC"7;
"S \NAC"
BN"3"143;
%"TAP"
"6","(-1525,2700)","0","mstr_standard","I37";
;
CDS_LIB"mstr_standard"
BODY_TYPE"PLUMBING"
HDL_TAP"TRUE";
"B \NAC \NWC"7;
"S \NAC"
BN"2"141;
%"TAP"
"6","(-1475,2900)","0","mstr_standard","I38";
;
CDS_LIB"mstr_standard"
BODY_TYPE"PLUMBING"
HDL_TAP"TRUE";
"B \NAC \NWC"6;
"S \NAC"
BN"5"144;
%"TAP"
"6","(-1475,2850)","0","mstr_standard","I39";
;
CDS_LIB"mstr_standard"
BODY_TYPE"PLUMBING"
HDL_TAP"TRUE";
"B \NAC \NWC"6;
"S \NAC"
BN"4"140;
%"TAP"
"6","(-1475,3000)","0","mstr_standard","I40";
;
CDS_LIB"mstr_standard"
BODY_TYPE"PLUMBING"
HDL_TAP"TRUE";
"B \NAC \NWC"6;
"S \NAC"
BN"7"146;
%"TAP"
"6","(-1475,2950)","0","mstr_standard","I41";
;
CDS_LIB"mstr_standard"
BODY_TYPE"PLUMBING"
HDL_TAP"TRUE";
"B \NAC \NWC"6;
"S \NAC"
BN"6"145;
%"TAP"
"6","(-1875,3300)","0","mstr_standard","I42";
;
CDS_LIB"mstr_standard"
BODY_TYPE"PLUMBING"
HDL_TAP"TRUE";
"B \NAC \NWC"8;
"S \NAC"
BN"3"137;
%"TAP"
"6","(-1875,3200)","0","mstr_standard","I43";
;
CDS_LIB"mstr_standard"
BODY_TYPE"PLUMBING"
HDL_TAP"TRUE";
"B \NAC \NWC"8;
"S \NAC"
BN"2"138;
%"TAP"
"6","(-1475,3400)","0","mstr_standard","I44";
;
CDS_LIB"mstr_standard"
BODY_TYPE"PLUMBING"
HDL_TAP"TRUE";
"B \NAC \NWC"11;
"S \NAC"
BN"0"133;
%"TAP"
"6","(-1475,3450)","0","mstr_standard","I45";
;
CDS_LIB"mstr_standard"
BODY_TYPE"PLUMBING"
HDL_TAP"TRUE";
"B \NAC \NWC"11;
"S \NAC"
BN"1"132;
%"TAP"
"6","(-1475,3500)","0","mstr_standard","I46";
;
CDS_LIB"mstr_standard"
BODY_TYPE"PLUMBING"
HDL_TAP"TRUE";
"B \NAC \NWC"10;
"S \NAC"
BN"0"131;
%"TAP"
"6","(-1475,3550)","0","mstr_standard","I47";
;
CDS_LIB"mstr_standard"
BODY_TYPE"PLUMBING"
HDL_TAP"TRUE";
"B \NAC \NWC"10;
"S \NAC"
BN"1"134;
%"TAP"
"6","(-1475,3650)","0","mstr_standard","I48";
;
CDS_LIB"mstr_standard"
BODY_TYPE"PLUMBING"
HDL_TAP"TRUE";
"B \NAC \NWC"12;
"S \NAC"
BN"0"130;
%"TAP"
"6","(25,1350)","2","mstr_standard","I49";
;
CDS_LIB"mstr_standard"
BODY_TYPE"PLUMBING"
HDL_TAP"TRUE";
"B \NAC \NWC"3;
"S \NAC"
BN"0"165;
%"PVPP_DEF"
"1","(-3575,1850)","0","mstr_symbols","I5";
;
VOLTAGE"2.5V"
CDS_LIB"mstr_symbols"
BODY_TYPE"PLUMBING"
HDL_POWER"PVPP_DEF";
"G\NAC"18;
%"TAP"
"6","(25,1500)","2","mstr_standard","I50";
;
CDS_LIB"mstr_standard"
BODY_TYPE"PLUMBING"
HDL_TAP"TRUE";
"B \NAC \NWC"3;
"S \NAC"
BN"3"163;
%"TAP"
"6","(25,1400)","2","mstr_standard","I51";
;
CDS_LIB"mstr_standard"
BODY_TYPE"PLUMBING"
HDL_TAP"TRUE";
"B \NAC \NWC"3;
"S \NAC"
BN"1"166;
%"TAP"
"6","(25,1450)","2","mstr_standard","I52";
;
CDS_LIB"mstr_standard"
BODY_TYPE"PLUMBING"
HDL_TAP"TRUE";
"B \NAC \NWC"3;
"S \NAC"
BN"2"164;
%"TAP"
"6","(25,1600)","2","mstr_standard","I53";
;
CDS_LIB"mstr_standard"
BODY_TYPE"PLUMBING"
HDL_TAP"TRUE";
"B \NAC \NWC"3;
"S \NAC"
BN"5"33;
%"TAP"
"6","(25,1550)","2","mstr_standard","I54";
;
CDS_LIB"mstr_standard"
BODY_TYPE"PLUMBING"
HDL_TAP"TRUE";
"B \NAC \NWC"3;
"S \NAC"
BN"4"160;
%"SCONN288_H44441003"
"4","(1475,1650)","0","mstr_sconn","I55";
;
CDS_SEC"4"
LOCATION"J6L2"
PART_NUMBER"H44441-003"
MATERIAL"SCONN"
BOM_SS"NOPOP"
PACK_TYPE"PIP"
BOM_COST"MEM"
CDS_LIB"mstr_sconn"
SEC_TYPE"PIP"
SEC"4"
CDS_LOCATION"J6L2"
ROOM"DDR4_CH_E";
"VDD<0>"
$PN"236"19;
"VDD<6>"
$PN"220"19;
"VDD<10>"
$PN"209"19;
"VDD<13>"
$PN"92"19;
"VDD<16>"
$PN"85"19;
"VDD<19>"
$PN"76"19;
"VDD<23>"
$PN"64"19;
"VDD<25>"
$PN"59"19;
"VTT<0>"
$PN"221"20;
"12V<1>"
$PN"1"16;
"12V<0>"
$PN"145"16;
"VDD<24>"
$PN"61"19;
"VDD<22>"
$PN"67"19;
"VDD<21>"
$PN"70"19;
"VDD<20>"
$PN"73"19;
"VDD<18>"
$PN"80"19;
"VDD<17>"
$PN"83"19;
"VDD<15>"
$PN"88"19;
"VDD<14>"
$PN"90"19;
"VDD<12>"
$PN"204"19;
"VDD<11>"
$PN"206"19;
"VDD<9>"
$PN"212"19;
"VDD<8>"
$PN"215"19;
"VDD<7>"
$PN"217"19;
"VDD<5>"
$PN"223"19;
"VDD<4>"
$PN"226"19;
"VDD<3>"
$PN"229"19;
"VDD<2>"
$PN"231"19;
"VDD<1>"
$PN"233"19;
"VPP<4>"
$PN"142"21;
"VPP<3>"
$PN"143"21;
"VPP<2>"
$PN"288"21;
"VPP<1>"
$PN"286"21;
"VPP<0>"
$PN"287"21;
"VTT<1>"
$PN"77"20;
%"TAP"
"6","(25,1700)","2","mstr_standard","I56";
;
CDS_LIB"mstr_standard"
BODY_TYPE"PLUMBING"
HDL_TAP"TRUE";
"B \NAC \NWC"3;
"S \NAC"
BN"7"162;
%"TAP"
"6","(25,1750)","2","mstr_standard","I57";
;
CDS_LIB"mstr_standard"
BODY_TYPE"PLUMBING"
HDL_TAP"TRUE";
"B \NAC \NWC"3;
"S \NAC"
BN"8"34;
%"TAP"
"6","(25,1650)","2","mstr_standard","I58";
;
CDS_LIB"mstr_standard"
BODY_TYPE"PLUMBING"
HDL_TAP"TRUE";
"B \NAC \NWC"3;
"S \NAC"
BN"6"161;
%"TAP"
"6","(25,1850)","2","mstr_standard","I59";
;
CDS_LIB"mstr_standard"
BODY_TYPE"PLUMBING"
HDL_TAP"TRUE";
"B \NAC \NWC"3;
"S \NAC"
BN"10"36;
%"TAP"
"6","(25,1800)","2","mstr_standard","I60";
;
CDS_LIB"mstr_standard"
BODY_TYPE"PLUMBING"
HDL_TAP"TRUE";
"B \NAC \NWC"3;
"S \NAC"
BN"9"35;
%"TAP"
"6","(25,1900)","2","mstr_standard","I61";
;
CDS_LIB"mstr_standard"
BODY_TYPE"PLUMBING"
HDL_TAP"TRUE";
"B \NAC \NWC"3;
"S \NAC"
BN"11"37;
%"TAP"
"6","(25,1950)","2","mstr_standard","I62";
;
CDS_LIB"mstr_standard"
BODY_TYPE"PLUMBING"
HDL_TAP"TRUE";
"B \NAC \NWC"3;
"S \NAC"
BN"12"29;
%"TAP"
"6","(25,2000)","2","mstr_standard","I63";
;
CDS_LIB"mstr_standard"
BODY_TYPE"PLUMBING"
HDL_TAP"TRUE";
"B \NAC \NWC"3;
"S \NAC"
BN"13"159;
%"TAP"
"6","(25,2150)","2","mstr_standard","I64";
;
CDS_LIB"mstr_standard"
BODY_TYPE"PLUMBING"
HDL_TAP"TRUE";
"B \NAC \NWC"3;
"S \NAC"
BN"16"120;
%"TAP"
"6","(25,2100)","2","mstr_standard","I65";
;
CDS_LIB"mstr_standard"
BODY_TYPE"PLUMBING"
HDL_TAP"TRUE";
"B \NAC \NWC"3;
"S \NAC"
BN"15"118;
%"TAP"
"6","(25,2050)","2","mstr_standard","I66";
;
CDS_LIB"mstr_standard"
BODY_TYPE"PLUMBING"
HDL_TAP"TRUE";
"B \NAC \NWC"3;
"S \NAC"
BN"14"119;
%"TAP"
"6","(25,2250)","2","mstr_standard","I67";
;
CDS_LIB"mstr_standard"
BODY_TYPE"PLUMBING"
HDL_TAP"TRUE";
"B \NAC \NWC"3;
"S \NAC"
BN"18"121;
%"TAP"
"6","(25,2200)","2","mstr_standard","I68";
;
CDS_LIB"mstr_standard"
BODY_TYPE"PLUMBING"
HDL_TAP"TRUE";
"B \NAC \NWC"3;
"S \NAC"
BN"17"117;
%"TAP"
"6","(25,2400)","2","mstr_standard","I69";
;
CDS_LIB"mstr_standard"
BODY_TYPE"PLUMBING"
HDL_TAP"TRUE";
"B \NAC \NWC"3;
"S \NAC"
BN"21"113;
%"TAP"
"6","(25,2350)","2","mstr_standard","I70";
;
CDS_LIB"mstr_standard"
BODY_TYPE"PLUMBING"
HDL_TAP"TRUE";
"B \NAC \NWC"3;
"S \NAC"
BN"20"112;
%"TAP"
"6","(25,2300)","2","mstr_standard","I71";
;
CDS_LIB"mstr_standard"
BODY_TYPE"PLUMBING"
HDL_TAP"TRUE";
"B \NAC \NWC"3;
"S \NAC"
BN"19"122;
%"TAP"
"6","(25,2450)","2","mstr_standard","I72";
;
CDS_LIB"mstr_standard"
BODY_TYPE"PLUMBING"
HDL_TAP"TRUE";
"B \NAC \NWC"3;
"S \NAC"
BN"22"114;
%"TAP"
"6","(25,2500)","2","mstr_standard","I73";
;
CDS_LIB"mstr_standard"
BODY_TYPE"PLUMBING"
HDL_TAP"TRUE";
"B \NAC \NWC"3;
"S \NAC"
BN"23"115;
%"TAP"
"6","(25,2650)","2","mstr_standard","I74";
;
CDS_LIB"mstr_standard"
BODY_TYPE"PLUMBING"
HDL_TAP"TRUE";
"B \NAC \NWC"3;
"S \NAC"
BN"26"107;
%"TAP"
"6","(25,2550)","2","mstr_standard","I75";
;
CDS_LIB"mstr_standard"
BODY_TYPE"PLUMBING"
HDL_TAP"TRUE";
"B \NAC \NWC"3;
"S \NAC"
BN"24"116;
%"TAP"
"6","(25,2600)","2","mstr_standard","I76";
;
CDS_LIB"mstr_standard"
BODY_TYPE"PLUMBING"
HDL_TAP"TRUE";
"B \NAC \NWC"3;
"S \NAC"
BN"25"109;
%"PVDDQ_DEF"
"1","(375,2200)","0","mstr_symbols","I77";
;
VOLTAGE"1.2V"
CDS_LIB"mstr_symbols"
BODY_TYPE"PLUMBING"
HDL_POWER"PVDDQ_DEF";
"G\NAC"19;
%"TAP"
"6","(25,2700)","2","mstr_standard","I78";
;
CDS_LIB"mstr_standard"
BODY_TYPE"PLUMBING"
HDL_TAP"TRUE";
"B \NAC \NWC"3;
"S \NAC"
BN"27"108;
%"TAP"
"6","(25,2750)","2","mstr_standard","I79";
;
CDS_LIB"mstr_standard"
BODY_TYPE"PLUMBING"
HDL_TAP"TRUE";
"B \NAC \NWC"3;
"S \NAC"
BN"28"110;
%"TAP"
"6","(25,2800)","2","mstr_standard","I80";
;
CDS_LIB"mstr_standard"
BODY_TYPE"PLUMBING"
HDL_TAP"TRUE";
"B \NAC \NWC"3;
"S \NAC"
BN"29"111;
%"TAP"
"6","(25,2900)","2","mstr_standard","I81";
;
CDS_LIB"mstr_standard"
BODY_TYPE"PLUMBING"
HDL_TAP"TRUE";
"B \NAC \NWC"3;
"S \NAC"
BN"31"104;
%"TAP"
"6","(25,2850)","2","mstr_standard","I82";
;
CDS_LIB"mstr_standard"
BODY_TYPE"PLUMBING"
HDL_TAP"TRUE";
"B \NAC \NWC"3;
"S \NAC"
BN"30"103;
%"TAP"
"6","(25,3050)","2","mstr_standard","I83";
;
CDS_LIB"mstr_standard"
BODY_TYPE"PLUMBING"
HDL_TAP"TRUE";
"B \NAC \NWC"3;
"S \NAC"
BN"34"106;
%"TAP"
"6","(25,3000)","2","mstr_standard","I84";
;
CDS_LIB"mstr_standard"
BODY_TYPE"PLUMBING"
HDL_TAP"TRUE";
"B \NAC \NWC"3;
"S \NAC"
BN"33"31;
%"TAP"
"6","(25,2950)","2","mstr_standard","I85";
;
CDS_LIB"mstr_standard"
BODY_TYPE"PLUMBING"
HDL_TAP"TRUE";
"B \NAC \NWC"3;
"S \NAC"
BN"32"105;
%"TAP"
"6","(25,3150)","2","mstr_standard","I86";
;
CDS_LIB"mstr_standard"
BODY_TYPE"PLUMBING"
HDL_TAP"TRUE";
"B \NAC \NWC"3;
"S \NAC"
BN"36"99;
%"TAP"
"6","(25,3100)","2","mstr_standard","I87";
;
CDS_LIB"mstr_standard"
BODY_TYPE"PLUMBING"
HDL_TAP"TRUE";
"B \NAC \NWC"3;
"S \NAC"
BN"35"100;
%"TAP"
"6","(25,3300)","2","mstr_standard","I88";
;
CDS_LIB"mstr_standard"
BODY_TYPE"PLUMBING"
HDL_TAP"TRUE";
"B \NAC \NWC"3;
"S \NAC"
BN"39"102;
%"TAP"
"6","(25,3250)","2","mstr_standard","I89";
;
CDS_LIB"mstr_standard"
BODY_TYPE"PLUMBING"
HDL_TAP"TRUE";
"B \NAC \NWC"3;
"S \NAC"
BN"38"98;
%"TAP"
"6","(25,3200)","2","mstr_standard","I90";
;
CDS_LIB"mstr_standard"
BODY_TYPE"PLUMBING"
HDL_TAP"TRUE";
"B \NAC \NWC"3;
"S \NAC"
BN"37"101;
%"TAP"
"6","(25,3350)","2","mstr_standard","I91";
;
CDS_LIB"mstr_standard"
BODY_TYPE"PLUMBING"
HDL_TAP"TRUE";
"B \NAC \NWC"3;
"S \NAC"
BN"40"93;
%"TAP"
"6","(25,3400)","2","mstr_standard","I92";
;
CDS_LIB"mstr_standard"
BODY_TYPE"PLUMBING"
HDL_TAP"TRUE";
"B \NAC \NWC"3;
"S \NAC"
BN"41"94;
%"TAP"
"6","(25,3550)","2","mstr_standard","I93";
;
CDS_LIB"mstr_standard"
BODY_TYPE"PLUMBING"
HDL_TAP"TRUE";
"B \NAC \NWC"3;
"S \NAC"
BN"44"97;
%"TAP"
"6","(25,3500)","2","mstr_standard","I94";
;
CDS_LIB"mstr_standard"
BODY_TYPE"PLUMBING"
HDL_TAP"TRUE";
"B \NAC \NWC"3;
"S \NAC"
BN"43"96;
%"TAP"
"6","(25,3450)","2","mstr_standard","I95";
;
CDS_LIB"mstr_standard"
BODY_TYPE"PLUMBING"
HDL_TAP"TRUE";
"B \NAC \NWC"3;
"S \NAC"
BN"42"95;
%"TAP"
"6","(25,3650)","2","mstr_standard","I96";
;
CDS_LIB"mstr_standard"
BODY_TYPE"PLUMBING"
HDL_TAP"TRUE";
"B \NAC \NWC"3;
"S \NAC"
BN"46"92;
%"TAP"
"6","(25,3600)","2","mstr_standard","I97";
;
CDS_LIB"mstr_standard"
BODY_TYPE"PLUMBING"
HDL_TAP"TRUE";
"B \NAC \NWC"3;
"S \NAC"
BN"45"91;
%"PVTT_DEF"
"1","(625,2350)","0","mstr_symbols","I98";
;
VOLTAGE"0.6V"
CDS_LIB"mstr_symbols"
BODY_TYPE"PLUMBING"
HDL_POWER"PVTT_DEF";
"G\NAC"20;
%"PVPP_DEF"
"1","(775,2650)","0","mstr_symbols","I99";
;
VOLTAGE"2.5V"
CDS_LIB"mstr_symbols"
BODY_TYPE"PLUMBING"
HDL_POWER"PVPP_DEF";
"G\NAC"21;
END.
